(kicad_pcb
	(version 20260206)
	(generator "pcbnew")
	(generator_version "10.0")
	(general
		(thickness 1.6)
		(legacy_teardrops no)
	)
	(paper "A4")
	(title_block
		(title "Wiwynn_Tioga_Pass_MB.brd")
		(comment 1 "Tioga Pass / footprints 3952-3959 of 4770")
	)
	(layers
		(0 "F.Cu" signal "TOP")
		(4 "In1.Cu" signal "L2GND")
		(6 "In2.Cu" signal "L3")
		(8 "In3.Cu" signal "L4GND")
		(10 "In4.Cu" signal "L5")
		(12 "In5.Cu" signal "L6GND")
		(14 "In6.Cu" signal "L7VCC")
		(16 "In7.Cu" signal "L8VCC")
		(18 "In8.Cu" signal "L9GND")
		(20 "In9.Cu" signal "L10")
		(22 "In10.Cu" signal "L11GND")
		(24 "In11.Cu" signal "L12")
		(26 "In12.Cu" signal "L13GND")
		(2 "B.Cu" signal "BOTTOM")
		(9 "F.Adhes" user "F.Adhesive")
		(11 "B.Adhes" user "B.Adhesive")
		(13 "F.Paste" user "Package Geometry/Pastemask Top")
		(15 "B.Paste" user "Package Geometry/Pastemask Bottom")
		(5 "F.SilkS" user "Ref Des/Silkscreen Top")
		(7 "B.SilkS" user "Ref Des/Silkscreen Bottom")
		(1 "F.Mask" user "Board Geometry/Soldermask Top")
		(3 "B.Mask" user "Board Geometry/Soldermask Bottom")
		(17 "Dwgs.User" user "User.Drawings")
		(19 "Cmts.User" user "User.Comments")
		(21 "Eco1.User" user "User.Eco1")
		(23 "Eco2.User" user "User.Eco2")
		(25 "Edge.Cuts" user "Board Geometry/Outline")
		(27 "Margin" user)
		(31 "F.CrtYd" user "Package Geometry/Place Bound Top")
		(29 "B.CrtYd" user "Package Geometry/Place Bound Bottom")
		(35 "F.Fab" user "Ref Des/Assembly Top")
		(33 "B.Fab" user "Ref Des/Assembly Bottom")
	)
	(footprint ""
		(layer "B.Cu")
		(at 392.041888 -115.315746 90)
		(property "Reference" "C2M16"
			(at 0 0 90)
			(layer "B.SilkS")
			(hide yes)
			(effects
				(font
					(size 1.27 1.27)
				)
				(justify mirror)
			)
		)
		(property "Value" ""
			(at 0 0 90)
			(layer "B.Fab")
			(effects
				(font
					(size 1.27 1.27)
				)
				(justify mirror)
			)
		)
		(duplicate_pad_numbers_are_jumpers no)
		(fp_poly
			(pts
				(xy -0.3048 -0.1016) (xy -0.3048 0.9906) (xy 0.3048 0.9906) (xy 0.3048 -0.1016)
			)
			(stroke
				(width 0)
				(type default)
			)
			(fill no)
			(layer "B.CrtYd")
		)
		(fp_line
			(start 0.3048 -0.1016)
			(end 0.3048 0.9906)
			(stroke
				(width 0.1)
				(type default)
			)
			(layer "B.Fab")
		)
		(fp_line
			(start -0.3048 -0.1016)
			(end 0.3048 -0.1016)
			(stroke
				(width 0.1)
				(type default)
			)
			(layer "B.Fab")
		)
		(fp_line
			(start 0.3048 0.9906)
			(end -0.3048 0.9906)
			(stroke
				(width 0.1)
				(type default)
			)
			(layer "B.Fab")
		)
		(fp_line
			(start -0.3048 0.9906)
			(end -0.3048 -0.1016)
			(stroke
				(width 0.1)
				(type default)
			)
			(layer "B.Fab")
		)
		(pad "1" smd rect
			(at 0 0 270)
			(size 0.508 0.508)
			(layers "B.Cu" "B.Mask" "B.Paste")
			(net "P3V3_STBY")
		)
		(pad "2" smd rect
			(at 0 0.889 270)
			(size 0.508 0.508)
			(layers "B.Cu" "B.Mask" "B.Paste")
			(net "GND")
		)
		(zone
			(layer "B.Cu")
			(hatch none 0.5)
			(connect_pads
				(clearance 0)
			)
			(min_thickness 0.25)
			(keepout
				(tracks allowed)
				(vias not_allowed)
				(pads allowed)
				(copperpour not_allowed)
				(footprints allowed)
			)
			(placement
				(enabled no)
				(sheetname "")
			)
			(fill
				(thermal_gap 0.5)
				(thermal_bridge_width 0.5)
				(island_removal_mode 0)
			)
			(polygon
				(pts
					(xy 392.295888 -115.569746) (xy 392.295888 -115.061746) (xy 392.676888 -115.061746) (xy 392.676888 -115.569746)
				)
			)
		)
		(zone
			(layer "B.Cu")
			(hatch none 0.5)
			(connect_pads
				(clearance 0)
			)
			(min_thickness 0.25)
			(keepout
				(tracks not_allowed)
				(vias allowed)
				(pads allowed)
				(copperpour not_allowed)
				(footprints allowed)
			)
			(placement
				(enabled no)
				(sheetname "")
			)
			(fill
				(thermal_gap 0.5)
				(thermal_bridge_width 0.5)
				(island_removal_mode 0)
			)
			(polygon
				(pts
					(xy 392.676888 -115.569746) (xy 392.676888 -115.061746) (xy 392.295888 -115.061746) (xy 392.295888 -115.569746)
				)
			)
		)
	)
	(footprint ""
		(layer "B.Cu")
		(at 28.564332 -31.06674 -90)
		(property "Reference" "R12W13"
			(at 0 0 90)
			(layer "B.SilkS")
			(hide yes)
			(effects
				(font
					(size 1.27 1.27)
				)
				(justify mirror)
			)
		)
		(property "Value" "*"
			(at -0.064008 -4.108196 270)
			(unlocked yes)
			(layer "B.Fab")
			(hide yes)
			(effects
				(font
					(size 1.27 1.016)
					(thickness 0.1524)
				)
				(justify mirror)
			)
		)
		(property "Device Type" "4D02R2F-GP_SMD-RG2-4D02R2F-GP,A"
			(at -0.064008 -5.632196 270)
			(unlocked yes)
			(layer "B.Fab")
			(hide yes)
			(effects
				(font
					(size 1.27 1.016)
					(thickness 0.1524)
				)
				(justify mirror)
			)
		)
		(duplicate_pad_numbers_are_jumpers no)
		(fp_line
			(start -0.508 -0.9398)
			(end 0.508 -0.9398)
			(stroke
				(width 0.1524)
				(type default)
			)
			(layer "B.SilkS")
		)
		(fp_line
			(start 0.508 -0.9398)
			(end 0.508 0.9398)
			(stroke
				(width 0.1524)
				(type default)
			)
			(layer "B.SilkS")
		)
		(fp_rect
			(start 0.508 0.9398)
			(end -0.508 -0.9398)
			(stroke
				(width 0)
				(type default)
			)
			(fill no)
			(layer "B.CrtYd")
		)
		(fp_rect
			(start 0.508 0.9398)
			(end -0.508 -0.9398)
			(stroke
				(width 0)
				(type default)
			)
			(fill no)
			(layer "B.Fab")
		)
		(pad "1" smd custom
			(at 0 -0.4445 90)
			(size 0.1397 0.1397)
			(layers "B.Cu" "B.Mask" "B.Paste")
			(net "P12V_STBY")
			(options
				(clearance outline)
				(anchor circle)
			)
			(primitives
				(gr_poly
					(pts
						(arc
							(start -0.1778 0.2794)
							(mid -0.249642 0.249642)
							(end -0.2794 0.1778)
						)
						(arc
							(start -0.2794 -0.1778)
							(mid -0.249642 -0.249642)
							(end -0.1778 -0.2794)
						)
						(arc
							(start 0.1778 -0.2794)
							(mid 0.249642 -0.249642)
							(end 0.2794 -0.1778)
						)
						(arc
							(start 0.2794 0.1778)
							(mid 0.249642 0.249642)
							(end 0.1778 0.2794)
						)
					)
					(width 0)
					(fill yes)
				)
			)
		)
		(pad "2" smd custom
			(at 0 0.4445 90)
			(size 0.1397 0.1397)
			(layers "B.Cu" "B.Mask" "B.Paste")
			(net "P12V_NVDIMM_GHJ_D")
			(options
				(clearance outline)
				(anchor circle)
			)
			(primitives
				(gr_poly
					(pts
						(arc
							(start -0.1778 0.2794)
							(mid -0.249642 0.249642)
							(end -0.2794 0.1778)
						)
						(arc
							(start -0.2794 -0.1778)
							(mid -0.249642 -0.249642)
							(end -0.1778 -0.2794)
						)
						(arc
							(start 0.1778 -0.2794)
							(mid 0.249642 -0.249642)
							(end 0.2794 -0.1778)
						)
						(arc
							(start 0.2794 0.1778)
							(mid 0.249642 0.249642)
							(end 0.1778 0.2794)
						)
					)
					(width 0)
					(fill yes)
				)
			)
		)
	)
	(footprint ""
		(layer "B.Cu")
		(at 20.14982 -134.965694 -90)
		(property "Reference" "R9M20"
			(at 0 0 90)
			(layer "B.SilkS")
			(hide yes)
			(effects
				(font
					(size 1.27 1.27)
				)
				(justify mirror)
			)
		)
		(property "Value" ""
			(at 0 0 90)
			(layer "B.Fab")
			(effects
				(font
					(size 1.27 1.27)
				)
				(justify mirror)
			)
		)
		(duplicate_pad_numbers_are_jumpers no)
		(fp_poly
			(pts
				(xy 0.2794 -0.1016) (xy -0.2794 -0.1016) (xy -0.2794 0.9906) (xy 0.2794 0.9906)
			)
			(stroke
				(width 0)
				(type default)
			)
			(fill no)
			(layer "B.CrtYd")
		)
		(fp_line
			(start -0.2794 0.9906)
			(end -0.2794 -0.1016)
			(stroke
				(width 0.1)
				(type default)
			)
			(layer "B.Fab")
		)
		(fp_line
			(start 0.2794 0.9906)
			(end -0.2794 0.9906)
			(stroke
				(width 0.1)
				(type default)
			)
			(layer "B.Fab")
		)
		(fp_line
			(start -0.2794 -0.1016)
			(end 0.2794 -0.1016)
			(stroke
				(width 0.1)
				(type default)
			)
			(layer "B.Fab")
		)
		(fp_line
			(start 0.2794 -0.1016)
			(end 0.2794 0.9906)
			(stroke
				(width 0.1)
				(type default)
			)
			(layer "B.Fab")
		)
		(pad "1" smd rect
			(at 0 0 90)
			(size 0.508 0.508)
			(layers "B.Cu" "B.Mask" "B.Paste")
			(net "SMB_LAN_STBY_LVC3_SCL")
		)
		(pad "2" smd rect
			(at 0 0.889 90)
			(size 0.508 0.508)
			(layers "B.Cu" "B.Mask" "B.Paste")
			(net "SMB_PIROM_CPU1_SCL")
		)
		(zone
			(layer "B.Cu")
			(hatch none 0.5)
			(connect_pads
				(clearance 0)
			)
			(min_thickness 0.25)
			(keepout
				(tracks not_allowed)
				(vias allowed)
				(pads allowed)
				(copperpour not_allowed)
				(footprints allowed)
			)
			(placement
				(enabled no)
				(sheetname "")
			)
			(fill
				(thermal_gap 0.5)
				(thermal_bridge_width 0.5)
				(island_removal_mode 0)
			)
			(polygon
				(pts
					(xy 19.51482 -134.711694) (xy 19.51482 -135.219694) (xy 19.89582 -135.219694) (xy 19.89582 -134.711694)
				)
			)
		)
		(zone
			(layer "B.Cu")
			(hatch none 0.5)
			(connect_pads
				(clearance 0)
			)
			(min_thickness 0.25)
			(keepout
				(tracks allowed)
				(vias not_allowed)
				(pads allowed)
				(copperpour not_allowed)
				(footprints allowed)
			)
			(placement
				(enabled no)
				(sheetname "")
			)
			(fill
				(thermal_gap 0.5)
				(thermal_bridge_width 0.5)
				(island_removal_mode 0)
			)
			(polygon
				(pts
					(xy 19.89582 -134.711694) (xy 19.89582 -135.219694) (xy 19.51482 -135.219694) (xy 19.51482 -134.711694)
				)
			)
		)
	)
	(footprint ""
		(layer "B.Cu")
		(at -3.22326 -121.47296 180)
		(property "Reference" "R9M14"
			(at 0 0 0)
			(layer "B.SilkS")
			(hide yes)
			(effects
				(font
					(size 1.27 1.27)
				)
				(justify mirror)
			)
		)
		(property "Value" ""
			(at 0 0 0)
			(layer "B.Fab")
			(effects
				(font
					(size 1.27 1.27)
				)
				(justify mirror)
			)
		)
		(duplicate_pad_numbers_are_jumpers no)
		(fp_rect
			(start 0.2794 -0.1016)
			(end -0.2794 0.9906)
			(stroke
				(width 0)
				(type default)
			)
			(fill no)
			(layer "B.CrtYd")
		)
		(fp_line
			(start 0.2794 0.9906)
			(end -0.2794 0.9906)
			(stroke
				(width 0.1)
				(type default)
			)
			(layer "B.Fab")
		)
		(fp_line
			(start 0.2794 -0.1016)
			(end 0.2794 0.9906)
			(stroke
				(width 0.1)
				(type default)
			)
			(layer "B.Fab")
		)
		(fp_line
			(start -0.2794 0.9906)
			(end -0.2794 -0.1016)
			(stroke
				(width 0.1)
				(type default)
			)
			(layer "B.Fab")
		)
		(fp_line
			(start -0.2794 -0.1016)
			(end 0.2794 -0.1016)
			(stroke
				(width 0.1)
				(type default)
			)
			(layer "B.Fab")
		)
		(pad "1" smd rect
			(at 0 0)
			(size 0.508 0.508)
			(layers "B.Cu" "B.Mask" "B.Paste")
			(net "SMB_PEHPCPU1_STBY_LVC3_R_SCL")
		)
		(pad "2" smd rect
			(at 0 0.889)
			(size 0.508 0.508)
			(layers "B.Cu" "B.Mask" "B.Paste")
			(net "SMB_PEHPCPU1_STBY_LVC3_SCL")
		)
		(zone
			(layer "B.Cu")
			(hatch none 0.5)
			(connect_pads
				(clearance 0)
			)
			(min_thickness 0.25)
			(keepout
				(tracks not_allowed)
				(vias allowed)
				(pads allowed)
				(copperpour not_allowed)
				(footprints allowed)
			)
			(placement
				(enabled no)
				(sheetname "")
			)
			(fill
				(thermal_gap 0.5)
				(thermal_bridge_width 0.5)
				(island_removal_mode 0)
			)
			(polygon
				(pts
					(xy -3.47726 -121.72696) (xy -2.96926 -121.72696) (xy -2.96926 -122.10796) (xy -3.47726 -122.10796)
				)
			)
		)
		(zone
			(layer "B.Cu")
			(hatch none 0.5)
			(connect_pads
				(clearance 0)
			)
			(min_thickness 0.25)
			(keepout
				(tracks allowed)
				(vias not_allowed)
				(pads allowed)
				(copperpour not_allowed)
				(footprints allowed)
			)
			(placement
				(enabled no)
				(sheetname "")
			)
			(fill
				(thermal_gap 0.5)
				(thermal_bridge_width 0.5)
				(island_removal_mode 0)
			)
			(polygon
				(pts
					(xy -3.47726 -121.72696) (xy -2.96926 -121.72696) (xy -2.96926 -122.10796) (xy -3.47726 -122.10796)
				)
			)
		)
	)
	(footprint ""
		(layer "B.Cu")
		(at 185.2549 -127.3048 180)
		(property "Reference" "R12W9"
			(at -1.01473 0.656336 270)
			(unlocked yes)
			(layer "B.SilkS")
			(effects
				(font
					(size 0.4064 0.254)
					(thickness 0.1524)
				)
				(justify mirror)
			)
		)
		(property "Value" ""
			(at 0 0 0)
			(layer "B.Fab")
			(effects
				(font
					(size 1.27 1.27)
				)
				(justify mirror)
			)
		)
		(duplicate_pad_numbers_are_jumpers no)
		(fp_poly
			(pts
				(xy 0.4953 -0.2032) (xy -0.4953 -0.2032) (xy -0.4953 1.6002) (xy 0.4953 1.6002)
			)
			(stroke
				(width 0)
				(type default)
			)
			(fill no)
			(layer "B.CrtYd")
		)
		(fp_line
			(start 0.4953 1.6002)
			(end 0.4953 -0.2032)
			(stroke
				(width 0.1)
				(type default)
			)
			(layer "B.Fab")
		)
		(fp_line
			(start 0.4953 -0.2032)
			(end -0.4953 -0.2032)
			(stroke
				(width 0.1)
				(type default)
			)
			(layer "B.Fab")
		)
		(fp_line
			(start -0.4953 1.6002)
			(end 0.4953 1.6002)
			(stroke
				(width 0.1)
				(type default)
			)
			(layer "B.Fab")
		)
		(fp_line
			(start -0.4953 -0.2032)
			(end -0.4953 1.6002)
			(stroke
				(width 0.1)
				(type default)
			)
			(layer "B.Fab")
		)
		(pad "1" smd rect
			(at 0 0)
			(size 0.762 0.889)
			(layers "B.Cu" "B.Mask" "B.Paste")
			(net "P12V_NVDIMM_DEF")
		)
		(pad "2" smd rect
			(at 0 1.397)
			(size 0.762 0.889)
			(layers "B.Cu" "B.Mask" "B.Paste")
			(net "PWRGD_PVDDQ_DEF_N")
		)
		(zone
			(layer "B.Cu")
			(hatch none 0.5)
			(connect_pads
				(clearance 0)
			)
			(min_thickness 0.25)
			(keepout
				(tracks not_allowed)
				(vias allowed)
				(pads allowed)
				(copperpour not_allowed)
				(footprints allowed)
			)
			(placement
				(enabled no)
				(sheetname "")
			)
			(fill
				(thermal_gap 0.5)
				(thermal_bridge_width 0.5)
				(island_removal_mode 0)
			)
			(polygon
				(pts
					(xy 184.8739 -128.2573) (xy 184.8739 -127.7493) (xy 185.6359 -127.7493) (xy 185.6359 -128.2573)
				)
			)
		)
		(zone
			(layer "B.Cu")
			(hatch none 0.5)
			(connect_pads
				(clearance 0)
			)
			(min_thickness 0.25)
			(keepout
				(tracks allowed)
				(vias not_allowed)
				(pads allowed)
				(copperpour not_allowed)
				(footprints allowed)
			)
			(placement
				(enabled no)
				(sheetname "")
			)
			(fill
				(thermal_gap 0.5)
				(thermal_bridge_width 0.5)
				(island_removal_mode 0)
			)
			(polygon
				(pts
					(xy 185.6359 -128.2573) (xy 185.6359 -127.7493) (xy 184.8739 -127.7493) (xy 184.8739 -128.2573)
				)
			)
		)
	)
	(footprint ""
		(layer "B.Cu")
		(at 427.4185 -23.368 90)
		(property "Reference" "R1U4"
			(at 0 0 90)
			(layer "B.SilkS")
			(hide yes)
			(effects
				(font
					(size 1.27 1.27)
				)
				(justify mirror)
			)
		)
		(property "Value" ""
			(at 0 0 90)
			(layer "B.Fab")
			(effects
				(font
					(size 1.27 1.27)
				)
				(justify mirror)
			)
		)
		(duplicate_pad_numbers_are_jumpers no)
		(fp_poly
			(pts
				(xy 0.2794 -0.1016) (xy -0.2794 -0.1016) (xy -0.2794 0.9906) (xy 0.2794 0.9906)
			)
			(stroke
				(width 0)
				(type default)
			)
			(fill no)
			(layer "B.CrtYd")
		)
		(fp_line
			(start 0.2794 -0.1016)
			(end 0.2794 0.9906)
			(stroke
				(width 0.1)
				(type default)
			)
			(layer "B.Fab")
		)
		(fp_line
			(start -0.2794 -0.1016)
			(end 0.2794 -0.1016)
			(stroke
				(width 0.1)
				(type default)
			)
			(layer "B.Fab")
		)
		(fp_line
			(start 0.2794 0.9906)
			(end -0.2794 0.9906)
			(stroke
				(width 0.1)
				(type default)
			)
			(layer "B.Fab")
		)
		(fp_line
			(start -0.2794 0.9906)
			(end -0.2794 -0.1016)
			(stroke
				(width 0.1)
				(type default)
			)
			(layer "B.Fab")
		)
		(pad "1" smd rect
			(at 0 0 270)
			(size 0.508 0.508)
			(layers "B.Cu" "B.Mask" "B.Paste")
			(net "FAN_TACH1")
		)
		(pad "2" smd rect
			(at 0 0.889 270)
			(size 0.508 0.508)
			(layers "B.Cu" "B.Mask" "B.Paste")
			(net "GND")
		)
		(zone
			(layer "B.Cu")
			(hatch none 0.5)
			(connect_pads
				(clearance 0)
			)
			(min_thickness 0.25)
			(keepout
				(tracks allowed)
				(vias not_allowed)
				(pads allowed)
				(copperpour not_allowed)
				(footprints allowed)
			)
			(placement
				(enabled no)
				(sheetname "")
			)
			(fill
				(thermal_gap 0.5)
				(thermal_bridge_width 0.5)
				(island_removal_mode 0)
			)
			(polygon
				(pts
					(xy 427.6725 -23.622) (xy 427.6725 -23.114) (xy 428.0535 -23.114) (xy 428.0535 -23.622)
				)
			)
		)
		(zone
			(layer "B.Cu")
			(hatch none 0.5)
			(connect_pads
				(clearance 0)
			)
			(min_thickness 0.25)
			(keepout
				(tracks not_allowed)
				(vias allowed)
				(pads allowed)
				(copperpour not_allowed)
				(footprints allowed)
			)
			(placement
				(enabled no)
				(sheetname "")
			)
			(fill
				(thermal_gap 0.5)
				(thermal_bridge_width 0.5)
				(island_removal_mode 0)
			)
			(polygon
				(pts
					(xy 428.0535 -23.622) (xy 428.0535 -23.114) (xy 427.6725 -23.114) (xy 427.6725 -23.622)
				)
			)
		)
	)
	(footprint ""
		(layer "B.Cu")
		(at 372.4275 -138.049 -90)
		(property "Reference" "C3M18"
			(at 0 0 90)
			(layer "B.SilkS")
			(hide yes)
			(effects
				(font
					(size 1.27 1.27)
				)
				(justify mirror)
			)
		)
		(property "Value" ""
			(at 0 0 90)
			(layer "B.Fab")
			(effects
				(font
					(size 1.27 1.27)
				)
				(justify mirror)
			)
		)
		(duplicate_pad_numbers_are_jumpers no)
		(fp_poly
			(pts
				(xy 0.4953 -0.2032) (xy -0.4953 -0.2032) (xy -0.4953 1.6002) (xy 0.4953 1.6002)
			)
			(stroke
				(width 0)
				(type default)
			)
			(fill no)
			(layer "B.CrtYd")
		)
		(fp_line
			(start -0.4953 1.6002)
			(end 0.4953 1.6002)
			(stroke
				(width 0.1)
				(type default)
			)
			(layer "B.Fab")
		)
		(fp_line
			(start 0.4953 1.6002)
			(end 0.4953 -0.2032)
			(stroke
				(width 0.1)
				(type default)
			)
			(layer "B.Fab")
		)
		(fp_line
			(start -0.4953 -0.2032)
			(end -0.4953 1.6002)
			(stroke
				(width 0.1)
				(type default)
			)
			(layer "B.Fab")
		)
		(fp_line
			(start 0.4953 -0.2032)
			(end -0.4953 -0.2032)
			(stroke
				(width 0.1)
				(type default)
			)
			(layer "B.Fab")
		)
		(pad "1" smd rect
			(at 0 0 90)
			(size 0.762 0.889)
			(layers "B.Cu" "B.Mask" "B.Paste")
			(net "P1V05_PCH_STBY_VCCA_PLL0")
		)
		(pad "2" smd rect
			(at 0 1.397 90)
			(size 0.762 0.889)
			(layers "B.Cu" "B.Mask" "B.Paste")
			(net "GND")
		)
		(zone
			(layer "B.Cu")
			(hatch none 0.5)
			(connect_pads
				(clearance 0)
			)
			(min_thickness 0.25)
			(keepout
				(tracks not_allowed)
				(vias allowed)
				(pads allowed)
				(copperpour not_allowed)
				(footprints allowed)
			)
			(placement
				(enabled no)
				(sheetname "")
			)
			(fill
				(thermal_gap 0.5)
				(thermal_bridge_width 0.5)
				(island_removal_mode 0)
			)
			(polygon
				(pts
					(xy 371.983 -137.668) (xy 371.983 -138.43) (xy 371.475 -138.43) (xy 371.475 -137.668)
				)
			)
		)
	)
	(footprint ""
		(layer "B.Cu")
		(at 259.5626 -140.081 90)
		(property "Reference" "C5G78"
			(at -1.64973 0.78994 180)
			(unlocked yes)
			(layer "B.SilkS")
			(effects
				(font
					(size 0.7874 0.5842)
					(thickness 0.1524)
				)
				(justify mirror)
			)
		)
		(property "Value" ""
			(at 0 0 90)
			(layer "B.Fab")
			(effects
				(font
					(size 1.27 1.27)
				)
				(justify mirror)
			)
		)
		(duplicate_pad_numbers_are_jumpers no)
		(fp_rect
			(start -0.7239 -0.2159)
			(end 0.7239 1.9939)
			(stroke
				(width 0)
				(type default)
			)
			(fill no)
			(layer "B.CrtYd")
		)
		(fp_line
			(start 0.7239 -0.2159)
			(end 0.7239 1.9939)
			(stroke
				(width 0.1)
				(type default)
			)
			(layer "B.Fab")
		)
		(fp_line
			(start -0.7239 -0.2159)
			(end 0.7239 -0.2159)
			(stroke
				(width 0.1)
				(type default)
			)
			(layer "B.Fab")
		)
		(fp_line
			(start 0.7239 1.9939)
			(end -0.7239 1.9939)
			(stroke
				(width 0.1)
				(type default)
			)
			(layer "B.Fab")
		)
		(fp_line
			(start -0.7239 1.9939)
			(end -0.7239 -0.2159)
			(stroke
				(width 0.1)
				(type default)
			)
			(layer "B.Fab")
		)
		(pad "1" smd rect
			(at 0 0 270)
			(size 1.27 1.016)
			(layers "B.Cu" "B.Mask" "B.Paste")
			(net "PVDDQ_DEF")
		)
		(pad "2" smd rect
			(at 0 1.778 270)
			(size 1.27 1.016)
			(layers "B.Cu" "B.Mask" "B.Paste")
			(net "GND")
		)
		(zone
			(layer "B.Cu")
			(hatch none 0.5)
			(connect_pads
				(clearance 0)
			)
			(min_thickness 0.25)
			(keepout
				(tracks not_allowed)
				(vias allowed)
				(pads allowed)
				(copperpour not_allowed)
				(footprints allowed)
			)
			(placement
				(enabled no)
				(sheetname "")
			)
			(fill
				(thermal_gap 0.5)
				(thermal_bridge_width 0.5)
				(island_removal_mode 0)
			)
			(polygon
				(pts
					(xy 260.0706 -139.446) (xy 260.8326 -139.446) (xy 260.8326 -140.716) (xy 260.0706 -140.716)
				)
			)
		)
	)
)
